(kicad_pcb
	(version 20260206)
	(generator "pcbnew")
	(generator_version "10.0")
	(general
		(thickness 1.6)
		(legacy_teardrops no)
	)
	(paper "A4")
	(title_block
		(title "01162023_DA0F0TEBIF0_F0T_Expander_BD_F_brd_V02_OCP.brd")
		(comment 1 "Grand Teton / footprint 6619 of 9728 (PEX0), pads 475-594 of 2397")
	)
	(layers
		(0 "F.Cu" signal "TOP")
		(4 "In1.Cu" signal "GND")
		(6 "In2.Cu" signal "VCC")
		(8 "In3.Cu" signal "VCC1")
		(10 "In4.Cu" signal "GND1")
		(12 "In5.Cu" signal "IN1")
		(14 "In6.Cu" signal "GND2")
		(16 "In7.Cu" signal "IN2")
		(18 "In8.Cu" signal "GND3")
		(20 "In9.Cu" signal "IN3")
		(22 "In10.Cu" signal "GND4")
		(24 "In11.Cu" signal "IN4")
		(26 "In12.Cu" signal "GND5")
		(28 "In13.Cu" signal "IN5")
		(30 "In14.Cu" signal "GND6")
		(32 "In15.Cu" signal "IN6")
		(34 "In16.Cu" signal "GND7")
		(2 "B.Cu" signal "BOTTOM")
		(9 "F.Adhes" user "F.Adhesive")
		(11 "B.Adhes" user "B.Adhesive")
		(13 "F.Paste" user "Package Geometry/Pastemask Top")
		(15 "B.Paste" user "Package Geometry/Pastemask Bottom")
		(5 "F.SilkS" user "Ref Des/Silkscreen Top")
		(7 "B.SilkS" user "Ref Des/Silkscreen Bottom")
		(1 "F.Mask" user "Board Geometry/Soldermask Top")
		(3 "B.Mask" user "Board Geometry/Soldermask Bottom")
		(17 "Dwgs.User" user "User.Drawings")
		(19 "Cmts.User" user "User.Comments")
		(21 "Eco1.User" user "User.Eco1")
		(23 "Eco2.User" user "User.Eco2")
		(25 "Edge.Cuts" user "Board Geometry/Outline")
		(27 "Margin" user)
		(31 "F.CrtYd" user "Package Geometry/Place Bound Top")
		(29 "B.CrtYd" user "Package Geometry/Place Bound Bottom")
		(35 "F.Fab" user "Ref Des/Assembly Top")
		(33 "B.Fab" user "Ref Des/Assembly Bottom")
	)
	(footprint ""
		(layer "F.Cu")
		(at 59.649868 -295.89984)
		(property "Reference" "PEX0"
			(at -3.360166 35.566858 0)
			(unlocked yes)
			(layer "F.SilkS")
			(effects
				(font
					(size 2.032 1.524)
					(thickness 0.1524)
				)
				(justify left)
			)
		)
		(property "Value" ""
			(at 0 0 0)
			(layer "F.Fab")
			(effects
				(font
					(size 1.27 1.27)
				)
			)
		)
		(duplicate_pad_numbers_are_jumpers no)
		(pad "AJ36" smd circle
			(at 10.450068 3.800094)
			(size 0.4572 0.4572)
			(layers "F.Cu" "F.Mask" "F.Paste")
			(net "GND")
		)
		(pad "AJ37" smd circle
			(at 11.400028 3.800094)
			(size 0.4572 0.4572)
			(layers "F.Cu" "F.Mask" "F.Paste")
			(net "GND")
		)
		(pad "AJ38" smd circle
			(at 12.349988 3.800094)
			(size 0.4572 0.4572)
			(layers "F.Cu" "F.Mask" "F.Paste")
			(net "UART_PEX0_CLI_TX")
		)
		(pad "AJ39" smd circle
			(at 13.299948 3.800094)
			(size 0.4572 0.4572)
			(layers "F.Cu" "F.Mask" "F.Paste")
			(net "Net_2846")
		)
		(pad "AJ40" smd circle
			(at 14.249908 3.800094)
			(size 0.4572 0.4572)
			(layers "F.Cu" "F.Mask" "F.Paste")
			(net "GND")
		)
		(pad "AJ41" smd circle
			(at 15.200122 3.800094)
			(size 0.4572 0.4572)
			(layers "F.Cu" "F.Mask" "F.Paste")
			(net "GND")
		)
		(pad "AJ42" smd circle
			(at 16.150082 3.800094)
			(size 0.4572 0.4572)
			(layers "F.Cu" "F.Mask" "F.Paste")
			(net "GND")
		)
		(pad "AJ43" smd circle
			(at 17.100042 3.800094)
			(size 0.4572 0.4572)
			(layers "F.Cu" "F.Mask" "F.Paste")
			(net "Net_2826")
		)
		(pad "AJ44" smd circle
			(at 18.050002 3.800094)
			(size 0.4572 0.4572)
			(layers "F.Cu" "F.Mask" "F.Paste")
			(net "Net_2810")
		)
		(pad "AJ45" smd circle
			(at 18.999962 3.800094)
			(size 0.4572 0.4572)
			(layers "F.Cu" "F.Mask" "F.Paste")
			(net "GND")
		)
		(pad "AJ46" smd circle
			(at 19.949922 3.800094)
			(size 0.4572 0.4572)
			(layers "F.Cu" "F.Mask" "F.Paste")
			(net "Net_2794")
		)
		(pad "AJ47" smd circle
			(at 20.899882 3.800094)
			(size 0.4572 0.4572)
			(layers "F.Cu" "F.Mask" "F.Paste")
			(net "Net_2778")
		)
		(pad "AJ48" smd circle
			(at 21.850096 3.800094)
			(size 0.4572 0.4572)
			(layers "F.Cu" "F.Mask" "F.Paste")
			(net "GND")
		)
		(pad "AJ49" smd circle
			(at 22.800056 3.800094)
			(size 0.4572 0.4572)
			(layers "F.Cu" "F.Mask" "F.Paste")
			(net "GND")
		)
		(pad "AK1" smd circle
			(at -22.800056 4.750054)
			(size 0.4572 0.4572)
			(layers "F.Cu" "F.Mask" "F.Paste")
			(net "GND")
		)
		(pad "AK2" smd circle
			(at -21.850096 4.750054)
			(size 0.4572 0.4572)
			(layers "F.Cu" "F.Mask" "F.Paste")
			(net "GND")
		)
		(pad "AK3" smd circle
			(at -20.899882 4.750054)
			(size 0.4572 0.4572)
			(layers "F.Cu" "F.Mask" "F.Paste")
			(net "GND")
		)
		(pad "AK4" smd circle
			(at -19.949922 4.750054)
			(size 0.4572 0.4572)
			(layers "F.Cu" "F.Mask" "F.Paste")
			(net "Net_494")
		)
		(pad "AK5" smd circle
			(at -18.999962 4.750054)
			(size 0.4572 0.4572)
			(layers "F.Cu" "F.Mask" "F.Paste")
			(net "Net_490")
		)
		(pad "AK6" smd circle
			(at -18.050002 4.750054)
			(size 0.4572 0.4572)
			(layers "F.Cu" "F.Mask" "F.Paste")
			(net "GND")
		)
		(pad "AK7" smd circle
			(at -17.100042 4.750054)
			(size 0.4572 0.4572)
			(layers "F.Cu" "F.Mask" "F.Paste")
			(net "Net_2910")
		)
		(pad "AK8" smd circle
			(at -16.150082 4.750054)
			(size 0.4572 0.4572)
			(layers "F.Cu" "F.Mask" "F.Paste")
			(net "GND")
		)
		(pad "AK9" smd circle
			(at -15.200122 4.750054)
			(size 0.4572 0.4572)
			(layers "F.Cu" "F.Mask" "F.Paste")
			(net "GND")
		)
		(pad "AK10" smd circle
			(at -14.249908 4.750054)
			(size 0.4572 0.4572)
			(layers "F.Cu" "F.Mask" "F.Paste")
			(net "P1V8_PEX")
		)
		(pad "AK11" smd circle
			(at -13.299948 4.750054)
			(size 0.4572 0.4572)
			(layers "F.Cu" "F.Mask" "F.Paste")
			(net "GND")
		)
		(pad "AK12" smd circle
			(at -12.349988 4.750054)
			(size 0.4572 0.4572)
			(layers "F.Cu" "F.Mask" "F.Paste")
			(net "P1V8_PEX")
		)
		(pad "AK13" smd circle
			(at -11.400028 4.750054)
			(size 0.4572 0.4572)
			(layers "F.Cu" "F.Mask" "F.Paste")
			(net "GND")
		)
		(pad "AK14" smd circle
			(at -10.450068 4.750054)
			(size 0.4572 0.4572)
			(layers "F.Cu" "F.Mask" "F.Paste")
			(net "P0V8_PEX0")
		)
		(pad "AK15" smd circle
			(at -9.500108 4.750054)
			(size 0.4572 0.4572)
			(layers "F.Cu" "F.Mask" "F.Paste")
			(net "GND")
		)
		(pad "AK16" smd circle
			(at -8.549894 4.750054)
			(size 0.4572 0.4572)
			(layers "F.Cu" "F.Mask" "F.Paste")
			(net "P0V8_SERDES_VDDA_PEX0")
		)
		(pad "AK17" smd circle
			(at -7.599934 4.750054)
			(size 0.4572 0.4572)
			(layers "F.Cu" "F.Mask" "F.Paste")
			(net "P0V8_SERDES_VDDA_PEX0")
		)
		(pad "AK18" smd circle
			(at -6.649974 4.750054)
			(size 0.4572 0.4572)
			(layers "F.Cu" "F.Mask" "F.Paste")
			(net "P0V8_SERDES_VDDA_PEX0")
		)
		(pad "AK19" smd circle
			(at -5.700014 4.750054)
			(size 0.4572 0.4572)
			(layers "F.Cu" "F.Mask" "F.Paste")
			(net "P0V8_SERDES_VDDA_PEX0")
		)
		(pad "AK20" smd circle
			(at -4.750054 4.750054)
			(size 0.4572 0.4572)
			(layers "F.Cu" "F.Mask" "F.Paste")
			(net "P0V8_SERDES_VDDA_PEX0")
		)
		(pad "AK21" smd circle
			(at -3.800094 4.750054)
			(size 0.4572 0.4572)
			(layers "F.Cu" "F.Mask" "F.Paste")
			(net "P0V8_SERDES_VDDA_PEX0")
		)
		(pad "AK22" smd circle
			(at -2.84988 4.750054)
			(size 0.4572 0.4572)
			(layers "F.Cu" "F.Mask" "F.Paste")
			(net "P0V8_SERDES_VDDA_PEX0")
		)
		(pad "AK23" smd circle
			(at -1.89992 4.750054)
			(size 0.4572 0.4572)
			(layers "F.Cu" "F.Mask" "F.Paste")
			(net "P0V8_SERDES_VDDA_PEX0")
		)
		(pad "AK24" smd circle
			(at -0.94996 4.750054)
			(size 0.4572 0.4572)
			(layers "F.Cu" "F.Mask" "F.Paste")
			(net "P0V8_SERDES_VDDA_PEX0")
		)
		(pad "AK25" smd circle
			(at 0 4.750054)
			(size 0.4572 0.4572)
			(layers "F.Cu" "F.Mask" "F.Paste")
			(net "P0V8_SERDES_VDDA_PEX0")
		)
		(pad "AK26" smd circle
			(at 0.94996 4.750054)
			(size 0.4572 0.4572)
			(layers "F.Cu" "F.Mask" "F.Paste")
			(net "P0V8_SERDES_VDDA_PEX0")
		)
		(pad "AK27" smd circle
			(at 1.89992 4.750054)
			(size 0.4572 0.4572)
			(layers "F.Cu" "F.Mask" "F.Paste")
			(net "P0V8_SERDES_VDDA_PEX0")
		)
		(pad "AK28" smd circle
			(at 2.84988 4.750054)
			(size 0.4572 0.4572)
			(layers "F.Cu" "F.Mask" "F.Paste")
			(net "P0V8_SERDES_VDDA_PEX0")
		)
		(pad "AK29" smd circle
			(at 3.800094 4.750054)
			(size 0.4572 0.4572)
			(layers "F.Cu" "F.Mask" "F.Paste")
			(net "P0V8_SERDES_VDDA_PEX0")
		)
		(pad "AK30" smd circle
			(at 4.750054 4.750054)
			(size 0.4572 0.4572)
			(layers "F.Cu" "F.Mask" "F.Paste")
			(net "P0V8_SERDES_VDDA_PEX0")
		)
		(pad "AK31" smd circle
			(at 5.700014 4.750054)
			(size 0.4572 0.4572)
			(layers "F.Cu" "F.Mask" "F.Paste")
			(net "P0V8_SERDES_VDDA_PEX0")
		)
		(pad "AK32" smd circle
			(at 6.649974 4.750054)
			(size 0.4572 0.4572)
			(layers "F.Cu" "F.Mask" "F.Paste")
			(net "P0V8_SERDES_VDDA_PEX0")
		)
		(pad "AK33" smd circle
			(at 7.599934 4.750054)
			(size 0.4572 0.4572)
			(layers "F.Cu" "F.Mask" "F.Paste")
			(net "P0V8_SERDES_VDDA_PEX0")
		)
		(pad "AK34" smd circle
			(at 8.549894 4.750054)
			(size 0.4572 0.4572)
			(layers "F.Cu" "F.Mask" "F.Paste")
			(net "GND")
		)
		(pad "AK35" smd circle
			(at 9.500108 4.750054)
			(size 0.4572 0.4572)
			(layers "F.Cu" "F.Mask" "F.Paste")
			(net "P1V8_PEX")
		)
		(pad "AK36" smd circle
			(at 10.450068 4.750054)
			(size 0.4572 0.4572)
			(layers "F.Cu" "F.Mask" "F.Paste")
			(net "GND")
		)
		(pad "AK37" smd circle
			(at 11.400028 4.750054)
			(size 0.4572 0.4572)
			(layers "F.Cu" "F.Mask" "F.Paste")
			(net "GND")
		)
		(pad "AK38" smd circle
			(at 12.349988 4.750054)
			(size 0.4572 0.4572)
			(layers "F.Cu" "F.Mask" "F.Paste")
			(net "UART_PEX0_CLI_BUF_RX")
		)
		(pad "AK39" smd circle
			(at 13.299948 4.750054)
			(size 0.4572 0.4572)
			(layers "F.Cu" "F.Mask" "F.Paste")
			(net "UART_PEX0_SDB_BUF_RX")
		)
		(pad "AK40" smd circle
			(at 14.249908 4.750054)
			(size 0.4572 0.4572)
			(layers "F.Cu" "F.Mask" "F.Paste")
			(net "GND")
		)
		(pad "AK41" smd circle
			(at 15.200122 4.750054)
			(size 0.4572 0.4572)
			(layers "F.Cu" "F.Mask" "F.Paste")
			(net "Net_2827")
		)
		(pad "AK42" smd circle
			(at 16.150082 4.750054)
			(size 0.4572 0.4572)
			(layers "F.Cu" "F.Mask" "F.Paste")
			(net "Net_2811")
		)
		(pad "AK43" smd circle
			(at 17.100042 4.750054)
			(size 0.4572 0.4572)
			(layers "F.Cu" "F.Mask" "F.Paste")
			(net "GND")
		)
		(pad "AK44" smd circle
			(at 18.050002 4.750054)
			(size 0.4572 0.4572)
			(layers "F.Cu" "F.Mask" "F.Paste")
			(net "GND")
		)
		(pad "AK45" smd circle
			(at 18.999962 4.750054)
			(size 0.4572 0.4572)
			(layers "F.Cu" "F.Mask" "F.Paste")
			(net "GND")
		)
		(pad "AK46" smd circle
			(at 19.949922 4.750054)
			(size 0.4572 0.4572)
			(layers "F.Cu" "F.Mask" "F.Paste")
			(net "GND")
		)
		(pad "AK47" smd circle
			(at 20.899882 4.750054)
			(size 0.4572 0.4572)
			(layers "F.Cu" "F.Mask" "F.Paste")
			(net "GND")
		)
		(pad "AK48" smd circle
			(at 21.850096 4.750054)
			(size 0.4572 0.4572)
			(layers "F.Cu" "F.Mask" "F.Paste")
			(net "Net_2795")
		)
		(pad "AK49" smd circle
			(at 22.800056 4.750054)
			(size 0.4572 0.4572)
			(layers "F.Cu" "F.Mask" "F.Paste")
			(net "Net_2779")
		)
		(pad "AL1" smd circle
			(at -22.800056 5.700014)
			(size 0.4572 0.4572)
			(layers "F.Cu" "F.Mask" "F.Paste")
			(net "GND")
		)
		(pad "AL2" smd circle
			(at -21.850096 5.700014)
			(size 0.4572 0.4572)
			(layers "F.Cu" "F.Mask" "F.Paste")
			(net "GND")
		)
		(pad "AL3" smd circle
			(at -20.899882 5.700014)
			(size 0.4572 0.4572)
			(layers "F.Cu" "F.Mask" "F.Paste")
			(net "GND")
		)
		(pad "AL4" smd circle
			(at -19.949922 5.700014)
			(size 0.4572 0.4572)
			(layers "F.Cu" "F.Mask" "F.Paste")
			(net "GND")
		)
		(pad "AL5" smd circle
			(at -18.999962 5.700014)
			(size 0.4572 0.4572)
			(layers "F.Cu" "F.Mask" "F.Paste")
			(net "GND")
		)
		(pad "AL6" smd circle
			(at -18.050002 5.700014)
			(size 0.4572 0.4572)
			(layers "F.Cu" "F.Mask" "F.Paste")
			(net "GND")
		)
		(pad "AL7" smd circle
			(at -17.100042 5.700014)
			(size 0.4572 0.4572)
			(layers "F.Cu" "F.Mask" "F.Paste")
			(net "GND")
		)
		(pad "AL8" smd circle
			(at -16.150082 5.700014)
			(size 0.4572 0.4572)
			(layers "F.Cu" "F.Mask" "F.Paste")
			(net "GND")
		)
		(pad "AL9" smd circle
			(at -15.200122 5.700014)
			(size 0.4572 0.4572)
			(layers "F.Cu" "F.Mask" "F.Paste")
			(net "GND")
		)
		(pad "AL10" smd circle
			(at -14.249908 5.700014)
			(size 0.4572 0.4572)
			(layers "F.Cu" "F.Mask" "F.Paste")
			(net "GND")
		)
		(pad "AL11" smd circle
			(at -13.299948 5.700014)
			(size 0.4572 0.4572)
			(layers "F.Cu" "F.Mask" "F.Paste")
			(net "GND")
		)
		(pad "AL12" smd circle
			(at -12.349988 5.700014)
			(size 0.4572 0.4572)
			(layers "F.Cu" "F.Mask" "F.Paste")
			(net "GND")
		)
		(pad "AL13" smd circle
			(at -11.400028 5.700014)
			(size 0.4572 0.4572)
			(layers "F.Cu" "F.Mask" "F.Paste")
			(net "GND")
		)
		(pad "AL14" smd circle
			(at -10.450068 5.700014)
			(size 0.4572 0.4572)
			(layers "F.Cu" "F.Mask" "F.Paste")
			(net "VSSA_SENSE")
		)
		(pad "AL15" smd circle
			(at -9.500108 5.700014)
			(size 0.4572 0.4572)
			(layers "F.Cu" "F.Mask" "F.Paste")
			(net "VDDA_SENSE")
		)
		(pad "AL16" smd circle
			(at -8.549894 5.700014)
			(size 0.4572 0.4572)
			(layers "F.Cu" "F.Mask" "F.Paste")
			(net "GND")
		)
		(pad "AL17" smd circle
			(at -7.599934 5.700014)
			(size 0.4572 0.4572)
			(layers "F.Cu" "F.Mask" "F.Paste")
			(net "GND")
		)
		(pad "AL18" smd circle
			(at -6.649974 5.700014)
			(size 0.4572 0.4572)
			(layers "F.Cu" "F.Mask" "F.Paste")
			(net "GND")
		)
		(pad "AL19" smd circle
			(at -5.700014 5.700014)
			(size 0.4572 0.4572)
			(layers "F.Cu" "F.Mask" "F.Paste")
			(net "GND")
		)
		(pad "AL20" smd circle
			(at -4.750054 5.700014)
			(size 0.4572 0.4572)
			(layers "F.Cu" "F.Mask" "F.Paste")
			(net "GND")
		)
		(pad "AL21" smd circle
			(at -3.800094 5.700014)
			(size 0.4572 0.4572)
			(layers "F.Cu" "F.Mask" "F.Paste")
			(net "GND")
		)
		(pad "AL22" smd circle
			(at -2.84988 5.700014)
			(size 0.4572 0.4572)
			(layers "F.Cu" "F.Mask" "F.Paste")
			(net "GND")
		)
		(pad "AL23" smd circle
			(at -1.89992 5.700014)
			(size 0.4572 0.4572)
			(layers "F.Cu" "F.Mask" "F.Paste")
			(net "GND")
		)
		(pad "AL24" smd circle
			(at -0.94996 5.700014)
			(size 0.4572 0.4572)
			(layers "F.Cu" "F.Mask" "F.Paste")
			(net "GND")
		)
		(pad "AL25" smd circle
			(at 0 5.700014)
			(size 0.4572 0.4572)
			(layers "F.Cu" "F.Mask" "F.Paste")
			(net "GND")
		)
		(pad "AL26" smd circle
			(at 0.94996 5.700014)
			(size 0.4572 0.4572)
			(layers "F.Cu" "F.Mask" "F.Paste")
			(net "GND")
		)
		(pad "AL27" smd circle
			(at 1.89992 5.700014)
			(size 0.4572 0.4572)
			(layers "F.Cu" "F.Mask" "F.Paste")
			(net "GND")
		)
		(pad "AL28" smd circle
			(at 2.84988 5.700014)
			(size 0.4572 0.4572)
			(layers "F.Cu" "F.Mask" "F.Paste")
			(net "GND")
		)
		(pad "AL29" smd circle
			(at 3.800094 5.700014)
			(size 0.4572 0.4572)
			(layers "F.Cu" "F.Mask" "F.Paste")
			(net "GND")
		)
		(pad "AL30" smd circle
			(at 4.750054 5.700014)
			(size 0.4572 0.4572)
			(layers "F.Cu" "F.Mask" "F.Paste")
			(net "GND")
		)
		(pad "AL31" smd circle
			(at 5.700014 5.700014)
			(size 0.4572 0.4572)
			(layers "F.Cu" "F.Mask" "F.Paste")
			(net "GND")
		)
		(pad "AL32" smd circle
			(at 6.649974 5.700014)
			(size 0.4572 0.4572)
			(layers "F.Cu" "F.Mask" "F.Paste")
			(net "GND")
		)
		(pad "AL33" smd circle
			(at 7.599934 5.700014)
			(size 0.4572 0.4572)
			(layers "F.Cu" "F.Mask" "F.Paste")
			(net "GND")
		)
		(pad "AL34" smd circle
			(at 8.549894 5.700014)
			(size 0.4572 0.4572)
			(layers "F.Cu" "F.Mask" "F.Paste")
			(net "GND")
		)
		(pad "AL35" smd circle
			(at 9.500108 5.700014)
			(size 0.4572 0.4572)
			(layers "F.Cu" "F.Mask" "F.Paste")
			(net "P1V8_PEX")
		)
		(pad "AL36" smd circle
			(at 10.450068 5.700014)
			(size 0.4572 0.4572)
			(layers "F.Cu" "F.Mask" "F.Paste")
			(net "GND")
		)
		(pad "AL37" smd circle
			(at 11.400028 5.700014)
			(size 0.4572 0.4572)
			(layers "F.Cu" "F.Mask" "F.Paste")
			(net "GND")
		)
		(pad "AL38" smd circle
			(at 12.349988 5.700014)
			(size 0.4572 0.4572)
			(layers "F.Cu" "F.Mask" "F.Paste")
			(net "Net_2877")
		)
		(pad "AL39" smd circle
			(at 13.299948 5.700014)
			(size 0.4572 0.4572)
			(layers "F.Cu" "F.Mask" "F.Paste")
			(net "UART_PEX0_SDB_TX")
		)
		(pad "AL40" smd circle
			(at 14.249908 5.700014)
			(size 0.4572 0.4572)
			(layers "F.Cu" "F.Mask" "F.Paste")
			(net "GND")
		)
		(pad "AL41" smd circle
			(at 15.200122 5.700014)
			(size 0.4572 0.4572)
			(layers "F.Cu" "F.Mask" "F.Paste")
			(net "GND")
		)
		(pad "AL42" smd circle
			(at 16.150082 5.700014)
			(size 0.4572 0.4572)
			(layers "F.Cu" "F.Mask" "F.Paste")
			(net "GND")
		)
		(pad "AL43" smd circle
			(at 17.100042 5.700014)
			(size 0.4572 0.4572)
			(layers "F.Cu" "F.Mask" "F.Paste")
			(net "Net_2828")
		)
		(pad "AL44" smd circle
			(at 18.050002 5.700014)
			(size 0.4572 0.4572)
			(layers "F.Cu" "F.Mask" "F.Paste")
			(net "Net_2812")
		)
		(pad "AL45" smd circle
			(at 18.999962 5.700014)
			(size 0.4572 0.4572)
			(layers "F.Cu" "F.Mask" "F.Paste")
			(net "GND")
		)
		(pad "AL46" smd circle
			(at 19.949922 5.700014)
			(size 0.4572 0.4572)
			(layers "F.Cu" "F.Mask" "F.Paste")
			(net "Net_2796")
		)
		(pad "AL47" smd circle
			(at 20.899882 5.700014)
			(size 0.4572 0.4572)
			(layers "F.Cu" "F.Mask" "F.Paste")
			(net "Net_2780")
		)
		(pad "AL48" smd circle
			(at 21.850096 5.700014)
			(size 0.4572 0.4572)
			(layers "F.Cu" "F.Mask" "F.Paste")
			(net "GND")
		)
		(pad "AL49" smd circle
			(at 22.800056 5.700014)
			(size 0.4572 0.4572)
			(layers "F.Cu" "F.Mask" "F.Paste")
			(net "GND")
		)
		(pad "AM1" smd circle
			(at -22.800056 6.649974)
			(size 0.4572 0.4572)
			(layers "F.Cu" "F.Mask" "F.Paste")
			(net "P4E_PEX0_STN3_RX_DN<48>")
		)
		(pad "AM2" smd circle
			(at -21.850096 6.649974)
			(size 0.4572 0.4572)
			(layers "F.Cu" "F.Mask" "F.Paste")
			(net "P4E_PEX0_STN3_RX_DP<48>")
		)
		(pad "AM3" smd circle
			(at -20.899882 6.649974)
			(size 0.4572 0.4572)
			(layers "F.Cu" "F.Mask" "F.Paste")
			(net "GND")
		)
		(pad "AM4" smd circle
			(at -19.949922 6.649974)
			(size 0.4572 0.4572)
			(layers "F.Cu" "F.Mask" "F.Paste")
			(net "GND")
		)
		(pad "AM5" smd circle
			(at -18.999962 6.649974)
			(size 0.4572 0.4572)
			(layers "F.Cu" "F.Mask" "F.Paste")
			(net "GND")
		)
		(pad "AM6" smd circle
			(at -18.050002 6.649974)
			(size 0.4572 0.4572)
			(layers "F.Cu" "F.Mask" "F.Paste")
			(net "GND")
		)
		(pad "AM7" smd circle
			(at -17.100042 6.649974)
			(size 0.4572 0.4572)
			(layers "F.Cu" "F.Mask" "F.Paste")
			(net "GND")
		)
		(pad "AM8" smd circle
			(at -16.150082 6.649974)
			(size 0.4572 0.4572)
			(layers "F.Cu" "F.Mask" "F.Paste")
			(net "P4E_PEX0_STN3_TX_DN<48>")
		)
	)
)
